 
 
Open CloudServer  
OCS Solid State Drive 
Version 2.1 
 
 
 
 
Author: 
Laura Caulfield, Software Engineer II, Microsoft 
 



Open Compute Project  Open CloudServer OCS Solid State Drive 
http://opencompute.org ii 
Revision History 
Date Version Description 
2/25/2015 2.0 Version 2.0 
8/14/2015 2.1 Removed AHCI as an option. 
Added Windows 10.   
Added support for out-of-band communication through SMBus.  
Increased detail for performance targets, debugging logs and FW 
update utility. 
 
  



Open Compute Project  Open CloudServer Solid State Drive 
http://opencompute.org iii 
 
© 2015 Microsoft Corporation. 
As of August 10, 2015, the following persons or entities have made this Specification available under the Open Web Foundation 
Final Specification Agreement (OWFa 1.0), which is available at http://www.openwebfoundation.org/legal/the-owf-1-0-
agreements/owfa-1-0 
 Microsoft Corporation.  
You can review the signed copies of the Open Web Foundation Agreement Version 1.0 for this Specification at 
http://opencompute.org/licensing/, which may also include additional parties to those listed above. 
Your use of this Specification may be subject to other third party rights. THIS SPECIFICATION IS PROVIDED "AS IS." The 
contributors expressly disclaim any warranties (express, implied, or otherwise), including implied warranties of merchantability, 
noninfringement, fitness for a particular purpose, or title, related to the Specification. The entire risk as to implementing or 
otherwise using the Specification is assumed by the Specification implementer and user. IN NO EVENT WILL ANY PARTY BE 
LIABLE TO ANY OTHER PARTY FOR LOST PROFITS OR ANY FORM OF INDIRECT, SPECIAL, INCIDENTAL, OR CONSEQUENTIAL 
DAMAGES OF ANY CHARACTER FROM ANY CAUSES OF ACTION OF ANY KIND WITH RESPECT TO THIS SPECIFICATION OR ITS 
GOVERNING AGREEMENT, WHETHER BASED ON BREACH OF CONTRACT, TORT (INCLUDING NEGLIGENCE), OR OTHERWISE, AND 
WHETHER OR NOT THE OTHER PARTY HAS BEEN ADVISED OF THE POSSIBILITY OF SUCH DAMAGE. 
CONTRIBUTORS AND LICENSORS OF THIS SPECIFICATION MAY HAVE MENTIONED CERTAIN TECHNOLOGIES THAT ARE MERELY 
REFERENCED WITHIN THIS SPECIFICATION AND NOT LICENSED UNDER THE OWF CLA OR OWFa. THE FOLLOWING IS A LIST OF 
MERELY REFERENCED TECHNOLOGY: INTELLIGENT PLATFORM MANAGEMENT INTERFACE (IPMI), I2C TRADEMARK OF PHILLIPS 
SEMICONDUCTOR. IMPLEMENTATION OF THESE TECHNOLOGIES MAY BE SUBJECT TO THEIR OWN LEGAL TERMS. 
  



 
iv August 14, 2015 
 
 
Contents 
1 Summary ....................................................................................................................................................... 1 
2 Reference Documents ................................................................................................................................... 2 
2.1 Applicable Documents .................................................................................................................................. 2 
2.2 Order of Preference ...................................................................................................................................... 2 
3 Operating System and Boot Requirements .................................................................................................... 2 
4 Performance .................................................................................................................................................. 3 
4.1 Bandwidth & Throughput ............................................................................................................................. 3 
4.2 Latency ......................................................................................................................................................... 3 
4.3 No I/O Throttling to Reduce Wear ............................................................................................................... 4 
5 Power ............................................................................................................................................................ 4 
6 Thermal & Mechanical .................................................................................................................................. 5 
6.1 Thermal ........................................................................................................................................................ 5 
6.2 Mechanical ................................................................................................................................................... 6 
7 Out of Band Management Interface .............................................................................................................. 7 
8 Endurance ..................................................................................................................................................... 9 
9 S.M.A.R.T. Attributes ..................................................................................................................................... 9 
10 Commands .................................................................................................................................................. 11 
10.1 Firmware Update ....................................................................................................................................... 11 
10.2 Disk Reconditioning Tool & Crypto-Erase ................................................................................................... 11 
10.3 Debugging Logs .......................................................................................................................................... 12 
10.4 Trim ............................................................................................................................................................ 12 
11 Unplanned Power Loss ................................................................................................................................ 12 
11.1 Drives with Volatile Write Cache ................................................................................................................ 13 
11.2 Drives with Non-Volatile Write Cache ........................................................................................................ 13 
11.2.1 Fast Flushing ...................................................................................................................................... 13 
11.3 Blade-supported Power-Loss Protection .................................................................................................... 13 
12 Data Security ............................................................................................................................................... 14 
 
  



Open Compute Project  Open CloudServer Solid State Drive 
http://opencompute.org v 
 
Table of Figures 
Figure 1: Air Property Pictorial ...................................................................................................................... 5 
Figure 2: Environmental Conditions for the Drive ........................................................................................ 6 
Figure 3: Top-Side Mechanical Exception ..................................................................................................... 7 
 
  



 
vi August 14, 2015 
 
Table of Tables 
Table 1: Device Summary .............................................................................................................................. 1 
Table 2: Reference Documents ..................................................................................................................... 2 
Table 3: Throughput Targets ......................................................................................................................... 3 
Table 4: Latency Targets ............................................................................................................................... 4 
Table 5: Additional SMART Attributes ........................................................................................................ 10 



 
http://opencompute.org 1 
 
1 Summary 
This specification, Open CloudServer Solid State Drive, OCS SSD, describes the low-cost, high-
performance flash-based storage devices deployed first in the Open CloudServer OCS Blade V2 
specification.  The OCS Blade V2 supports four PCI-Express riser cards and eight Open CloudServer Solid 
State Drive M.2 modules.  The Table 1 briefly describes the required features. 
Table 1: Device Summary 
Parameter Value 
Form Factor M.2 
Dimensions 22mm x 110mm (preferred) 
Hardware Protocol PCIe Generation 3, x4 (preferred) 
Software Protocol NVMe 1.2 
Capacity 960GB 
Endurance 
3 DWPD over 3 years, or 
1.3 DWPD over 3 years (preferred), or 
0.5 DWPD over 3 years 
Default Maximum Power 6W RMS over 100µs, 9.9W peak1 
Unpowered Retention 1 week – 1 month 
Life (MTTF/AFR) 1.5M hrs. / 0.5% (JEDEC Specification) 
Ambient Operating Temperature 0˚C – 50 ˚C 
Duty Cycle 100% 
Sector Size 512 Bytes 
*1 GB = 1,000,000,000 Bytes 
                                                           
 
 
1 Peak current no higher than 3A, 10us pulse width 



 
2 August 14, 2015 
 
2 Reference Documents 
This section lists the applicable reference documents and defines the order of preference. 
2.1 Applicable Documents 
Table 2 lists additional specifications to which the OCS SSD adheres.  
Table 2: Reference Documents 
Reference Description 
SMBus Technical Note April 2015 Technical Note: NVMe Basic Management Command, NVM 
Express, Revision 1.0a, April 2015 
SMBus Change Notice PCI-SIG engineering change notice, PCI-SIG, August 2014 
OCS FW Update “OCS Component Firmware Update Utility Specification” revision 0.02, 
Microsoft, June 2015 
M.2 “PCI Express M.2 Specification” Revision 0.7a, version 1.0.  PCI Express, 2013. 
NVM Express “NVM Express” Revision 1.2. Intel, 2014. 
PCI Express “PCI Express Base Specification.”  Revision 3.1. PCI Express, 2014. 
SNIA “Solid State Storage (SSS) Performance Test Specification (PTS) Enterprise” 
Version 1.0.  Advanced Storage and Information Technology (SNIA), 2011. 
JEDEC 218 “Solid-State Drive (SSD) Requirements and Endurance Test Method” JEDEC 
Solid State Technology Association (JEDEC), 2011. 
2.2 Order of Preference 
In the event of a conflict between this specification and references cited herein, this specification shall 
take precedence. 
3 Operating System and Boot Requirements 
The OCS SSD must support the following requirements. 



Open Compute Project  Open CloudServer Solid State Drive 
http://opencompute.org 3 
 
 The drive must support 64-bit Windows Server: WinPE and Windows Server 2012 R2. 
 The drive must be able to boot all supported versions of windows. 
 As a non-boot drive, the drive must be present in UEFI/BIOS. 
 Trimmed addresses must provide the performance and reliability benefits of additional OP. 
4 Performance 
The drive must meet the performance targets with these assumptions:  
 Entropy of all workloads is 100% (uncompressible) 
 Active range is 100% 
 Maximum power draw as specified  
 Operations are aligned to 4kB address boundaries 
 Performance targets include overheads from NTFS 
The vendor must provide a performance test report as defined by the SNIA Solid State Storage 
Performance Test Specification (PTSE). 
4.1 Bandwidth & Throughput 
The drive must meet or exceed the 6W performance targets list below.   
Table 3: Throughput Targets 
Metric 6W Target 
Sequential Read (MB/s)* 1600 
Sequential Write (MB/s)* 750 
Random Read (4kB IOPS) 150k 
Random Write (4kB IOPS) 30k 
Random Read/Write Mix 
(70/30 4kB IOPS) 
50k 
*MB = 106 Bytes 
4.2 Latency 
Random read latency must match or beat the distribution listed below under the following test 
conditions. 
 Queue Depth = 1 
 Drive is trimmed then written sequentially with 2MB accesses 
 Drive is near End-of-Life 



 
4 August 14, 2015 
 
 256kB sequential writes  with the rate adjusted so that 10% of the volume is writes , or  
256kB random writes  with the rate adjusted so that 5 % of the volume is writes   
(whichever is worse) 
Table 4: Latency Targets 
 
 4kB ( µs ) 8kB ( µs ) 64kB ( µs ) Operations  
Needed 
in Test* 
Average  240  250 450 -- 
99 % (2 nines) 300  360 770 >100 
99.9 % (3 nines) 400  380 1,000 >1,000 
99.99 % (4 nines) 500  550 3,000 >10,000 
99.999 % (5 nines) 1,000 2,000 3,500 >1e5 
99.9999 % (6 nines) 3,000 4,000 5,000 >1e6  
99.99999 % (7 nines) 5,000 6,000 8,000 >1e7 
99.999999 % (8 nines) 7,000 8,000 10,000 >1e8 
99.9999999 % (9 nines) 9,000 10,000 15,000 >1e9 
Maximum Timeout  11,000 12,000 20,000 -- 
*The test must apply the minimum number of operations listed in the right-most column. 
4.3 No I/O Throttling to Reduce Wear 
All SSD solutions are to provide performance consistent with the capabilities of the flash and controller.  
The drive: 
 Must not throttle the performance for the purpose of distributing wear on the flash over time 
 Must continue to allow writes as long as possible after the media wear indicator reaches 100% 
5 Power 
The drive must support dynamic switching between power states in which the host can perform I/O.   
The drive must report at least one power state for each level: 
 Required: Maximum of 6W,  
 Optional: Maximum of 8W and 10W 
Some blade configurations may leverage the optional power states for higher performance, but there is 
no guarantee.   
Drives must allow switching between operational power states through the Get Features and Set 
Features command with the Power Management feature identifier (see Figure 111 in Section 5.14.1.2 in 
the NVMe 1.2 specification).     



Open Compute Project  Open CloudServer Solid State Drive 
http://opencompute.org 5 
 
The supported operational power states shall be returned from the Get Features command with the 
Power Management feature identifier.  The Set Features command with Power Management feature 
identifier shall switch between the different supported operational power states.   
If the drive supports the Autonomous Power State Transition feature, it shall be disable-able through 
the Autonomous Power State Transition Enable (APSTE) in the Autonomous Power State Transition Set 
Feature command. 
6 Thermal & Mechanical 
6.1 Thermal 
The SSD must thermally protect itself from overheating.   
The drive must signal the host when its temperature is too high through a Temperature Async Event 
Notification. 
The environment in which the memory cards are expected to operate may vary from position to position 
within the server.  To best represent this environment, the air temperature and speed properties are 
defined as measured in Figure 1. 
 
Figure 1: Air Property Pictorial 
The guidelines for the expected environment are shown in Figure 2.  The theoretical full performance 
line represents the worst case conditions in which the memory card is expected to operate at full 
performance.  The memory cards are expected to operate, but allowed to do so at a reduced 
performance in the conditions between the full performance line and the throttled performance line. 
The drive must operate in the thermal environment as shown in Figure 2. 


 
6 August 14, 2015 
 
 
Figure 2: Environmental Conditions for the Drive 
 
6.2 Mechanical 
This section outlines the mechanical requirements. 
 The connector on the M.2 card must use 30 micro-inches of gold plating.                                      
 The server can mechanically support module lengths of 60mm, 80mm or 110mm and uses a 
Socket 3 connector.   
 The card shall conform to the geometry provided by the PCI Express M.2 Specification, section 
2.3.4.4, card type 22110. 
Note: Including capacitors for the power safe feature has proven difficult with the current height 
specification.  The OCS V2 blade can accommodate a top-side component height of 3.0 mm, as shown 
in Figure 3.  Vendors are granted an exception for this specification if 3.0 mm height is met.  Vendors 


Open Compute Project  Open CloudServer Solid State Drive 
http://opencompute.org 7 
 
are encouraged to meet the M.2 specification to ensure compatibility with future OCS systems and 
non-OCS systems. 
 
Figure 3: Top-Side Mechanical Exception 
 
7 Out of Band Management Interface 
The drive must implement the SMBus pins defined in the SMBus Change Notice. 
The drive must follow the raw SMBus protocol defined below, and in the SMBus Technical Note. 



 
8 August 14, 2015 
 
Command Code Offset Dexcription 
0  As defined in the technical note from 
NVMe working group.  
8  As defined in the technical note from 
NVMe working group. 
32 32 Major Firmware Version Number: 8 
characters that indicate the version of SSD 
controller’s firmware, incremented only 
for major revisions.  First character is 
transmitted first. 
33 Minor Firmware Version Number: 8 
characters that indicate the version of SSD 
controller’s firmware, incremented for 
minor revisions.  First character is 
transmitted first. 
34 Capacitor Health: An indicator of the 
health of the capacitors (if present).  This 
shall be expressed as a percentage of 
charge the capacitor is able to hold.  If no 
capacitor exists, value shall be 255. 
35 Temperature Throttling: 0x01 indicates 
the drive is throttling performance to 
prevent overheating. 
36 Power Consumption: Current power 
consumption of NAND, Controller and 
other SSD components in Watts.  If the 
SSD does not have a mechanism to 
measure power, it should return 255. 
(optional) 
38:37 Reserved: Shall be set to 0000h. 
39 PEC: An 8 bit CRC calculated over the slice 
address, command code, second slave 
address and returned data.  Algorithm in 
SMBus Specifications.   
40+ 255:40 Vendor Specific: This data structure shall 
not exceed the maximum read length of 
255 specified in the SMBus version 3 
specification.  Preferably length is not 
greater than 32 for compatibility with 
SMBus 2.0, additional blocks shall be on 8 
byte boundaries. 
 



Open Compute Project  Open CloudServer Solid State Drive 
http://opencompute.org 9 
 
8 Endurance 
Drives must be able to sustain their rated DWPD over 3 years for the reasonable worst-case workload: 
 4kB accesses aligned to 4kB boundaries 
 Random pattern of addresses 
 100% active range 
 100% full drive 
 0% compressible data 
The drive must switch to read-only mode when there is an insufficient amount of working NAND to 
support writes, and generate an async notification before switching to read-only mode. 
9 S.M.A.R.T. Attributes 
Consistent access to SMART attributes across all drives is required.  The NVMe specification provides 
this through log pages.  Drives must implement the SMART / Health log page defined in the NVMe 
specification. 
 SMART commands may not block IO for more than 30ms. 
 SMART values will be updated before each read so that the value reported is the most current.  
 The vendor-specific log page (0xC) shall be 512 bytes and define the following attributes: 
  



 
10 August 14, 2015 
 
Table 5: Additional SMART Attributes 
Bytes Attribute Name Attribute Description 
15:0 Medium Units Written Contains the number of 512 byte data 
units the medium has been written; this 
value includes metadata written to the 
non-out-of-band area in the medium. This 
value is reported in thousands (i.e., a 
value of 1 corresponds to 1000 units of 
512 bytes written) and is rounded up. 
When the LBA size is a value other than 
512 bytes, the controller shall convert the 
amount of data written to 512 byte units.   
16 Capacitor Healthˠ An indicator of the health of the 
capacitors (if present).  This shall be 
expressed as a percentage of charge the 
capacitor is able to hold.   
17 Supported Features Bit 0: 1 indicates a super capacitor exists 
Bits 1-7: Reserved 
32:18 Temperature Throttling  Tracks how much performance is 
throttled to prevent overheating.  The 
attribute reports the number of dies 
multiplied by how long the dies are 
turned off (in minutes).  Resets when the 
drive power cycles.  Saturates and does 
not wrap.* 
33 Power Consumption (optional) Current power consumption of NAND, 
Controller and other SSD components in 
Watts.  If the SSD does not have a 
mechanism to measure power, it should 
return 255. 
34 Wear Range Delta Returns the difference between the 
percentage of used endurance of the 
most-worn block and the least worn 
block: 
(% used of most-worn) – (% used of least-
worn) 
35 Unaligned I/O Count of the number of unaligned IOs 
performed by the host.  This counter 
should be resettable and should not wrap. 
33:36 Mapped LBAs Number of LBAs the map is tracking 
511:37 Reserved  
ˠThis requirement is optional if the vendor provides compelling information in the datasheet about the 
high reliability of the capacitors used in the drive 
  



Open Compute Project  Open CloudServer Solid State Drive 
http://opencompute.org 11 
 
10 Commands 
The drive must support the commands specified in the NVMe 1.2 specification, and must also operate 
with the Microsoft drivers included with Windows since version 8.1 / Windows server 2012 R2. 
10.1 Firmware Update 
Drives must implement firmware updates according to the process defined in the NVMe specification.  
The device must support a minimum of 2 slots for firmware update and may support up to 7.   
For Windows 2012 environments, firmware update utilities must meet the following reqirements, and 
those defined in the OCS Firmware Update specification: 
 Fully scriptable through command line interface (no GUI or user interaction required) 
 Runs in WinPE and Windows Server 2012 R2 (64-bit) 
 Returns an error level or exit status of 0 (Error_SUCCESS) if the update completed successfully 
 (Optional) Log files to provide additional information (errors, error details, successfully 
completed steps, etc.) 
For Windows 10 environments, the drive shall update firmware with the following powershell 
command-lets: 
 Get-StorageFirmwareInformation 
 Update-StorageFirmware  
10.2 Disk Reconditioning Tool & Crypto-Erase 
The following commands are necessary to return the OCS SSD as close as possible to Fresh-Out-of-Box 
(FOB) shipping state.  FOB includes resetting all FTL state relating to block-mapping tables and garbage 
collection logic and erase all stale or invalid data from the flash.  
The drive must encrypt all data, and the secure erase command must operate quickly by simply erasing 
the key.  NVMe supports secure erase setting of Cryptographic Erase (see section 5.13 Figure 111 for 
more info). 
Drives must return to FOB state after combination of Format NVM and Crypto-erase 



 
12 August 14, 2015 
 
10.3 Debugging Logs 
The drive must provide access to its debugging logs.  The logs should contain enough information to 
determine root cause.  Their format will be vendor specific with the vendor providing a tool to consume 
the logs.   
Drive must use both log pages 0xC1 and 0xC2 for vendor-specific debugging logs. 
For log page(s) that do not contain any data, the drive shall fail the get log command 
For log pages that contain data, the first 32 bytes of the log page data shall contain a 32-byte header in 
the format (below), followed by the log page data. 
Bytes Name Description 
0 Log Page ID Either 0xC1 or 0xC2  
1 Reserved Must be 0   
3:2 Flags it 0: static; if set, log page contains static 
data.  If clear, log page contains dynamic 
data 
 
Bit 1: Namespace-Specific; if set, log page 
contains namespace specific data.  If 
clear, log page contains device data 
 
Bit 2-15: reserved; reserved bits must be 0 
7:4 Log Page Size (B) Size of log page in bytes 
15:8 Data Change Intervals (ms) Change interval of data in milliseconds; If 
static data, value is 0 
31:16 Reserved 16 reserved bytes with value of 0 
 
Vendors must provide a CLI tool that runs in Windows to parse the debugging logs for their drive.   
10.4 Trim 
In accordance with the NVMe specification, after trim, the controller shall return all zeros, all ones, or 
the last data written to the associated LBA.   
11 Unplanned Power Loss 
This section details requirements for behavior of write cache due to unplanned power loss. 
 High endurance drives must have a non-volatile write cache 



Open Compute Project  Open CloudServer Solid State Drive 
http://opencompute.org 13 
 
 Low endurance drives may have a volatile write cache 
11.1 Drives with Volatile Write Cache 
A drive with a volatile write cache is one whose data, in DRAM and/or SRAM, is not guaranteed to be 
written to non-volatile media on loss of power.     
11.2 Drives with Non-Volatile Write Cache 
The following types of media are defined as non-volatile caches: 
 volatile media (such as DRAM and SRAM) protected by capacitance 
   non-volatile media 
 drives supporting the PCIe reset Non-Volatile assist signal 
If the drive uses volatile media and capacitor health is compromised, the cache is no longer considered 
nonvolatile, and the drive must disable the volatile write cache and alert the host.   
Drives must alert the host to failed capacitors through the Device Reliability Async event.   
11.2.1 Fast Flushing 
The performance of drives with non-volatile write caches should not be noticeably degraded by flush, 
and the PLP-backed cache(s) should enable fast performance. 
 FUA – forced unit access should be fast 
 Flush Cache should not degrade performance 
 SET FEATURE write-cache disable 
The drive should still flush data to flash when the drive has been idle for at least 20ms or power has 
failed.  The host must be able to dynamically disable these performance optimizations. 
11.3 Blade-supported Power-Loss Protection 
OCS v2.0 servers shall support drives with volatile write caches by leveraging the server backup power 
supply. 
To support this scenario, drives must flush all data to non-volatile storage within 1s of the PCIe reset 
(PERST) signal.  After receiving the PCIe reset (PERST) signal, the drive must not drive any pins. 



 
14 August 14, 2015 
 
12 Data Security 
The drive must implement the subset of TCG protocol methods described in Microsoft’s Encrypted Hard 
Drive Device Guide (called the “eDrive” standard).  Microsoft has published the requirements on MSDN:  
http://msdn.microsoft.com/en-us/library/windows/hardware/br259095.aspx 
Drives must follow the eDrive security standard.   